FILE_TYPE = MACRO_DRAWING;
SET COLOR_WIRE YELLOW;
SET COLOR_PROP ORANGE;
SET COLOR_DOT WHITE;
SET COLOR_ARC YELLOW;
SET COLOR_BODY GREEN;
SET COLOR_NOTE PURPLE;
SET PROP_DISPLAY VALUE;
SET PAGE_NUMBER P196;
FORCEADD QUANTA_TITLE_BLOCK_C..1
(0 0);
FORCEPROP 1 LAST CUSTOM_TXT_CDS <NAME_2>
J 0
(-3175 50);
FORCEPROP 1 LAST CUSTOM_TXT_CDS <NAME_1>
J 0
(-3175 175);
FORCEPROP 1 LAST CUSTOM_TXT_CDS <Q_NUMBER>
J 0
(-1403 103);
DISPLAY 1.212766 (-1403 103);
FORCEPROP 1 LAST CUSTOM_TXT_CDS <Q_PROJ>
J 0
(-2382 102);
DISPLAY 1.212766 (-2382 102);
FORCEPROP 1 LAST CUSTOM_TXT_CDS <Q_REV>
J 0
(-184 103);
DISPLAY 1.212766 (-184 103);
FORCEPROP 1 LAST CUSTOM_TXT_CDS <CON_LAST_MODIFIED>
J 0
(-1885 15);
DISPLAY 0.978723 (-1885 15);
FORCEPROP 1 LAST CUSTOM_TXT_CDS <CON_PAGE_NUM> OF <CON_TOTAL_PAGES>
J 0
(-446 18);
DISPLAY 0.978723 (-446 18);
FORCEPROP 1 LAST Q_TITLE Blank
J 0
(-9366 26);
DISPLAY 2.446809 (-9366 26);
PAINT GREEN (-9366 26);
FORCEPROP 1 LAST CDS_LMAN_SYM_OUTLINE -9475,6775,100,-125
J 0
(0 0);
DISPLAY 0.468085 (0 0);
PAINT GREEN (0 0);
DISPLAY INVISIBLE (0 0);
FORCEPROP 2 LAST CDS_LIB pure_quanta
J 0
(0 0);
DISPLAY INVISIBLE (0 0);
FORCEPROP 2 LAST PAGE_BORDER TRUE
J 0
(-7890 5250);
DISPLAY 0.638298 (-7890 5250);
PAINT PINK (-7890 5250);
DISPLAY INVISIBLE (-7890 5250);
FORCEPROP 2 LAST CDS_XR_PAGE_TITLE CR-221 : @T6G_MB_LIB.T6G(SCH_1):PAGE221
J 0
(-7890 5250);
DISPLAY 0.638298 (-7890 5250);
PAINT PINK (-7890 5250);
DISPLAY INVISIBLE (-7890 5250);
FORCEPROP 2 LAST CUSTOM_TXT_CDS <XR_PAGE_TITLE>
J 0
(-7890 5250);
DISPLAY 0.638298 (-7890 5250);
PAINT PINK (-7890 5250);
DISPLAY INVISIBLE (-7890 5250);
FORCEPROP 1 LAST COMMENT_BODY TRUE
J 0
(12 -13);
DISPLAY 0.978723 (12 -13);
PAINT GREEN (12 -13);
DISPLAY INVISIBLE (12 -13);
FORCEPROP 1 LAST Q_DEPT BU9
J 1
(-3763 49);
DISPLAY 1.957447 (-3763 49);
PAINT GREEN (-3763 49);
DISPLAY INVISIBLE (-3763 49);
FORCEPROP 0 LAST CDS_CON_LAST_MODIFIED Thu Aug 24 10:15:24 2023
J 0
(-1885 15);
DISPLAY INVISIBLE (-1885 15);
QUIT
